(kicad_pcb
	(version 20241229)
	(generator "pcbnew")
	(generator_version "9.0")
	(general
		(thickness 1.62)
		(legacy_teardrops no)
	)
	(paper "A3")
	(title_block
		(title "COM Express 7 Baseboard")
		(date "2025-02-04")
		(rev "1.1.2")
		(company "Antmicro Ltd")
		(comment 1 "www.antmicro.com")
		(comment 9 "footprints 736-740 of 802")
	)
	(layers
		(0 "F.Cu" signal)
		(4 "In1.Cu" signal)
		(6 "In2.Cu" signal)
		(8 "In3.Cu" signal)
		(10 "In4.Cu" signal)
		(12 "In5.Cu" signal)
		(14 "In6.Cu" signal)
		(2 "B.Cu" signal)
		(9 "F.Adhes" user "F.Adhesive")
		(11 "B.Adhes" user "B.Adhesive")
		(13 "F.Paste" user)
		(15 "B.Paste" user)
		(5 "F.SilkS" user "F.Silkscreen")
		(7 "B.SilkS" user "B.Silkscreen")
		(1 "F.Mask" user)
		(3 "B.Mask" user)
		(17 "Dwgs.User" user "User.Drawings")
		(19 "Cmts.User" user "User.Comments")
		(21 "Eco1.User" user "User.Eco1")
		(23 "Eco2.User" user "User.Eco2")
		(25 "Edge.Cuts" user)
		(27 "Margin" user)
		(31 "F.CrtYd" user "F.Courtyard")
		(29 "B.CrtYd" user "B.Courtyard")
		(35 "F.Fab" user)
		(33 "B.Fab" user)
	)
	(footprint "antmicro-footprints:SC70-3"
		(layer "B.Cu")
		(at 113.63 105.2 90)
		(property "Reference" "D3"
			(at 1.46 -0.79 180)
			(layer "B.SilkS")
			(effects
				(font
					(size 0.7 0.7)
					(thickness 0.15)
				)
				(justify right bottom mirror)
			)
		)
		(property "Value" "TPD2E2U06_SC70"
			(at 0 -2.3 90)
			(layer "B.Fab")
			(effects
				(font
					(size 0.7 0.7)
					(thickness 0.15)
				)
				(justify right bottom mirror)
			)
		)
		(property "Datasheet" "https://www.ti.com/lit/ds/symlink/tpd2e2u06.pdf?ts=1706006131823&ref_url=https%253A%252F%252Fwww.ti.com%252Finterface%252Fdiodes%252Fesd-protection-diodes%252Fproducts.html"
			(at 0 0 90)
			(layer "F.Fab")
			(hide yes)
			(effects
				(font
					(size 1.27 1.27)
					(thickness 0.15)
				)
			)
		)
		(property "Author" "Antmicro"
			(at 218.41 -8.67 0)
			(layer "B.Fab")
			(hide yes)
			(effects
				(font
					(size 1 1)
					(thickness 0.15)
				)
				(justify mirror)
			)
		)
		(property "License" "Apache-2.0"
			(at 218.41 -8.67 0)
			(layer "B.Fab")
			(hide yes)
			(effects
				(font
					(size 1 1)
					(thickness 0.15)
				)
				(justify mirror)
			)
		)
		(property "MPN" "TPD2E2U06DCKR"
			(at 218.41 -8.67 0)
			(layer "B.Fab")
			(hide yes)
			(effects
				(font
					(size 1 1)
					(thickness 0.15)
				)
				(justify mirror)
			)
		)
		(property "Manufacturer" "Texas Instruments"
			(at 218.41 -8.67 0)
			(layer "B.Fab")
			(hide yes)
			(effects
				(font
					(size 1 1)
					(thickness 0.15)
				)
				(justify mirror)
			)
		)
		(sheetname "2xUSB3.0+RJ45")
		(sheetfile "usb3+rj45.kicad_sch")
		(attr smd)
		(fp_line
			(start 0.627 -1.001)
			(end -0.3 -1)
			(stroke
				(width 0.15)
				(type solid)
			)
			(layer "B.SilkS")
		)
		(fp_line
			(start 0.627 -1.001)
			(end 0.627 -0.6)
			(stroke
				(width 0.15)
				(type solid)
			)
			(layer "B.SilkS")
		)
		(fp_line
			(start 0.627 0.999)
			(end 0.627 0.6)
			(stroke
				(width 0.15)
				(type solid)
			)
			(layer "B.SilkS")
		)
		(fp_line
			(start 0.627 0.999)
			(end -0.3 1)
			(stroke
				(width 0.15)
				(type solid)
			)
			(layer "B.SilkS")
		)
		(fp_line
			(start 0.9 -1.3)
			(end 0.9 -0.4)
			(stroke
				(width 0.05)
				(type solid)
			)
			(layer "B.CrtYd")
		)
		(fp_line
			(start -0.9 -1.3)
			(end 0.9 -1.3)
			(stroke
				(width 0.05)
				(type solid)
			)
			(layer "B.CrtYd")
		)
		(fp_line
			(start -0.9 -1)
			(end -0.9 -1.3)
			(stroke
				(width 0.05)
				(type solid)
			)
			(layer "B.CrtYd")
		)
		(fp_line
			(start -1.4 -1)
			(end -0.9 -1)
			(stroke
				(width 0.05)
				(type solid)
			)
			(layer "B.CrtYd")
		)
		(fp_line
			(start 1.4 -0.4)
			(end 1.4 0.4)
			(stroke
				(width 0.05)
				(type solid)
			)
			(layer "B.CrtYd")
		)
		(fp_line
			(start 0.9 -0.4)
			(end 1.4 -0.4)
			(stroke
				(width 0.05)
				(type solid)
			)
			(layer "B.CrtYd")
		)
		(fp_line
			(start 1.4 0.4)
			(end 0.9 0.4)
			(stroke
				(width 0.05)
				(type solid)
			)
			(layer "B.CrtYd")
		)
		(fp_line
			(start 0.9 0.4)
			(end 0.9 1.3)
			(stroke
				(width 0.05)
				(type solid)
			)
			(layer "B.CrtYd")
		)
		(fp_line
			(start -0.9 1)
			(end -0.9 1.3)
			(stroke
				(width 0.05)
				(type solid)
			)
			(layer "B.CrtYd")
		)
		(fp_line
			(start -1.4 1)
			(end -1.4 -1)
			(stroke
				(width 0.05)
				(type solid)
			)
			(layer "B.CrtYd")
		)
		(fp_line
			(start -1.4 1)
			(end -0.9 1)
			(stroke
				(width 0.05)
				(type solid)
			)
			(layer "B.CrtYd")
		)
		(fp_line
			(start 0.9 1.3)
			(end -0.9 1.3)
			(stroke
				(width 0.05)
				(type solid)
			)
			(layer "B.CrtYd")
		)
		(fp_rect
			(start -0.623 0.999)
			(end 0.627 -1.001)
			(stroke
				(width 0.15)
				(type solid)
			)
			(fill no)
			(layer "B.Fab")
		)
		(pad "1" smd rect
			(at -1.051 0.65)
			(size 0.6 0.6)
			(layers "B.Cu" "B.Mask" "B.Paste")
			(net 125 "/2xUSB3.0+RJ45/P2_D-")
			(pinfunction "1")
			(pintype "passive")
			(teardrops
				(best_length_ratio 0.2)
				(max_length 1)
				(best_width_ratio 0.9)
				(max_width 2)
				(curved_edges yes)
				(filter_ratio 0.9)
				(enabled yes)
				(allow_two_segments yes)
				(prefer_zone_connections yes)
			)
		)
		(pad "2" smd rect
			(at -1.051 -0.65)
			(size 0.6 0.6)
			(layers "B.Cu" "B.Mask" "B.Paste")
			(net 126 "/2xUSB3.0+RJ45/P2_D+")
			(pinfunction "2")
			(pintype "passive")
			(teardrops
				(best_length_ratio 0.2)
				(max_length 1)
				(best_width_ratio 0.9)
				(max_width 2)
				(curved_edges yes)
				(filter_ratio 0.9)
				(enabled yes)
				(allow_two_segments yes)
				(prefer_zone_connections yes)
			)
		)
		(pad "3" smd rect
			(at 1.05 0)
			(size 0.6 0.6)
			(layers "B.Cu" "B.Mask" "B.Paste")
			(net 1 "GND")
			(pinfunction "3")
			(pintype "passive")
			(teardrops
				(best_length_ratio 0.2)
				(max_length 1)
				(best_width_ratio 0.9)
				(max_width 2)
				(curved_edges yes)
				(filter_ratio 0.9)
				(enabled yes)
				(allow_two_segments yes)
				(prefer_zone_connections yes)
			)
		)
	)
	(footprint "antmicro-footprints:C_0603_1608Metric"
		(layer "B.Cu")
		(at 116.9 92.01)
		(descr "Capacitor SMD 0603")
		(tags "capacitor 0603")
		(property "Reference" "C19"
			(at -1.1 1.55 0)
			(layer "B.SilkS")
			(effects
				(font
					(size 0.7 0.7)
					(thickness 0.15)
				)
				(justify right bottom mirror)
			)
		)
		(property "Value" "C_22u_16V_0603"
			(at -1.42757 -1.770288 0)
			(layer "B.Fab")
			(effects
				(font
					(size 0.7 0.7)
					(thickness 0.15)
				)
				(justify right bottom mirror)
			)
		)
		(property "Datasheet" "https://product.samsungsem.com/mlcc/CL10A226MO7JZN.do"
			(at 0 0 0)
			(layer "F.Fab")
			(hide yes)
			(effects
				(font
					(size 1.27 1.27)
					(thickness 0.15)
				)
			)
		)
		(property "Author" "Antmicro"
			(at 0 0 0)
			(layer "B.Fab")
			(hide yes)
			(effects
				(font
					(size 1 1)
					(thickness 0.15)
				)
				(justify mirror)
			)
		)
		(property "Dielectric" ""
			(at 0 0 0)
			(layer "B.Fab")
			(hide yes)
			(effects
				(font
					(size 1 1)
					(thickness 0.15)
				)
				(justify mirror)
			)
		)
		(property "License" "Apache-2.0"
			(at 0 0 0)
			(layer "B.Fab")
			(hide yes)
			(effects
				(font
					(size 1 1)
					(thickness 0.15)
				)
				(justify mirror)
			)
		)
		(property "MPN" "CL10A226MO7JZNC"
			(at 0 0 0)
			(layer "B.Fab")
			(hide yes)
			(effects
				(font
					(size 1 1)
					(thickness 0.15)
				)
				(justify mirror)
			)
		)
		(property "Manufacturer" "Samsung Electro-Mechanics"
			(at 0 0 0)
			(layer "B.Fab")
			(hide yes)
			(effects
				(font
					(size 1 1)
					(thickness 0.15)
				)
				(justify mirror)
			)
		)
		(property "Public" "False"
			(at 0 0 0)
			(layer "B.Fab")
			(hide yes)
			(effects
				(font
					(size 1 1)
					(thickness 0.15)
				)
				(justify mirror)
			)
		)
		(property "Val" "22u"
			(at 0 0 0)
			(layer "B.Fab")
			(hide yes)
			(effects
				(font
					(size 1 1)
					(thickness 0.15)
				)
				(justify mirror)
			)
		)
		(property "Voltage" "16V"
			(at 0 0 0)
			(layer "B.Fab")
			(hide yes)
			(effects
				(font
					(size 1 1)
					(thickness 0.15)
				)
				(justify mirror)
			)
		)
		(sheetname "2xUSB3.0+RJ45")
		(sheetfile "usb3+rj45.kicad_sch")
		(attr smd)
		(fp_line
			(start 0.15 -0.4)
			(end -0.15 -0.4)
			(stroke
				(width 0.15)
				(type solid)
			)
			(layer "B.SilkS")
		)
		(fp_line
			(start 0.15 0.4)
			(end -0.15 0.4)
			(stroke
				(width 0.15)
				(type solid)
			)
			(layer "B.SilkS")
		)
		(fp_rect
			(start -1.25 0.65)
			(end 1.25 -0.65)
			(stroke
				(width 0.05)
				(type solid)
			)
			(fill no)
			(layer "B.CrtYd")
		)
		(fp_rect
			(start -0.8 0.4)
			(end 0.8 -0.4)
			(stroke
				(width 0.15)
				(type solid)
			)
			(fill no)
			(layer "B.Fab")
		)
		(pad "1" smd roundrect
			(at -0.7 0)
			(size 0.8 1)
			(layers "B.Cu" "B.Mask" "B.Paste")
			(roundrect_rratio 0.2)
			(net 1 "GND")
			(pintype "passive")
			(teardrops
				(best_length_ratio 0.2)
				(max_length 1)
				(best_width_ratio 0.9)
				(max_width 2)
				(curved_edges yes)
				(filter_ratio 0.9)
				(enabled yes)
				(allow_two_segments yes)
				(prefer_zone_connections yes)
			)
		)
		(pad "2" smd roundrect
			(at 0.7 0)
			(size 0.8 1)
			(layers "B.Cu" "B.Mask" "B.Paste")
			(roundrect_rratio 0.2)
			(net 52 "+5V")
			(pintype "passive")
			(teardrops
				(best_length_ratio 0.2)
				(max_length 1)
				(best_width_ratio 0.9)
				(max_width 2)
				(curved_edges yes)
				(filter_ratio 0.9)
				(enabled yes)
				(allow_two_segments yes)
				(prefer_zone_connections yes)
			)
		)
	)
	(footprint "antmicro-footprints:R_0402_1005Metric"
		(layer "B.Cu")
		(at 139.74 138.36 180)
		(descr "Resistor SMD 0402")
		(tags "resistor SMD 0402")
		(property "Reference" "R287"
			(at 0.79 -0.75 0)
			(layer "B.SilkS")
			(effects
				(font
					(size 0.7 0.7)
					(thickness 0.15)
				)
				(justify left bottom mirror)
			)
		)
		(property "Value" "R_10k_0402"
			(at -1.011843 -1.772047 0)
			(layer "B.Fab")
			(effects
				(font
					(size 0.7 0.7)
					(thickness 0.15)
				)
				(justify left bottom mirror)
			)
		)
		(property "Datasheet" "https://www.bourns.com/docs/product-datasheets/cr.pdf"
			(at 0 0 180)
			(layer "F.Fab")
			(hide yes)
			(effects
				(font
					(size 1.27 1.27)
					(thickness 0.15)
				)
			)
		)
		(property "Author" "Antmicro"
			(at 279.48 276.72 0)
			(layer "B.Fab")
			(hide yes)
			(effects
				(font
					(size 1 1)
					(thickness 0.15)
				)
				(justify mirror)
			)
		)
		(property "License" "Apache-2.0"
			(at 279.48 276.72 0)
			(layer "B.Fab")
			(hide yes)
			(effects
				(font
					(size 1 1)
					(thickness 0.15)
				)
				(justify mirror)
			)
		)
		(property "MPN" "CR0402-FX-1002GLF"
			(at 279.48 276.72 0)
			(layer "B.Fab")
			(hide yes)
			(effects
				(font
					(size 1 1)
					(thickness 0.15)
				)
				(justify mirror)
			)
		)
		(property "Manufacturer" "Bourns"
			(at 279.48 276.72 0)
			(layer "B.Fab")
			(hide yes)
			(effects
				(font
					(size 1 1)
					(thickness 0.15)
				)
				(justify mirror)
			)
		)
		(property "Public" "False"
			(at 279.48 276.72 0)
			(layer "B.Fab")
			(hide yes)
			(effects
				(font
					(size 1 1)
					(thickness 0.15)
				)
				(justify mirror)
			)
		)
		(property "Tolerance" "1%"
			(at 279.48 276.72 0)
			(layer "B.Fab")
			(hide yes)
			(effects
				(font
					(size 1 1)
					(thickness 0.15)
				)
				(justify mirror)
			)
		)
		(property "Val" "10k"
			(at 279.48 276.72 0)
			(layer "B.Fab")
			(hide yes)
			(effects
				(font
					(size 1 1)
					(thickness 0.15)
				)
				(justify mirror)
			)
		)
		(sheetname "KR to SFI #2")
		(sheetfile "kr_sfi.kicad_sch")
		(attr smd)
		(fp_rect
			(start -0.925 0.47)
			(end 0.925 -0.47)
			(stroke
				(width 0.05)
				(type default)
			)
			(fill no)
			(layer "B.CrtYd")
		)
		(fp_rect
			(start -0.5 0.25)
			(end 0.5 -0.25)
			(stroke
				(width 0.15)
				(type solid)
			)
			(fill no)
			(layer "B.Fab")
		)
		(pad "1" smd roundrect
			(at -0.48 0 180)
			(size 0.59 0.64)
			(layers "B.Cu" "B.Mask" "B.Paste")
			(roundrect_rratio 0.25)
			(net 1 "GND")
			(pintype "passive")
			(teardrops
				(best_length_ratio 0.2)
				(max_length 1)
				(best_width_ratio 0.9)
				(max_width 2)
				(curved_edges yes)
				(filter_ratio 0.9)
				(enabled yes)
				(allow_two_segments yes)
				(prefer_zone_connections yes)
			)
		)
		(pad "2" smd roundrect
			(at 0.48 0 180)
			(size 0.59 0.64)
			(layers "B.Cu" "B.Mask" "B.Paste")
			(roundrect_rratio 0.25)
			(net 673 "/2xSFP+/KR to SFI #2/PRBSEN")
			(pintype "passive")
			(teardrops
				(best_length_ratio 0.2)
				(max_length 1)
				(best_width_ratio 0.9)
				(max_width 2)
				(curved_edges yes)
				(filter_ratio 0.9)
				(enabled yes)
				(allow_two_segments yes)
				(prefer_zone_connections yes)
			)
		)
	)
	(footprint "antmicro-footprints:C_0603_1608Metric"
		(layer "B.Cu")
		(at 148.7 73.16 180)
		(descr "Capacitor SMD 0603")
		(tags "capacitor 0603")
		(property "Reference" "C80"
			(at -3.3 -0.5 0)
			(layer "B.SilkS")
			(effects
				(font
					(size 0.7 0.7)
					(thickness 0.15)
				)
				(justify left bottom mirror)
			)
		)
		(property "Value" "C_22u_16V_0603"
			(at -1.42757 -1.770288 0)
			(layer "B.Fab")
			(effects
				(font
					(size 0.7 0.7)
					(thickness 0.15)
				)
				(justify left bottom mirror)
			)
		)
		(property "Datasheet" "https://product.samsungsem.com/mlcc/CL10A226MO7JZN.do"
			(at 0 0 180)
			(layer "F.Fab")
			(hide yes)
			(effects
				(font
					(size 1.27 1.27)
					(thickness 0.15)
				)
			)
		)
		(property "Author" "Antmicro"
			(at 297.4 146.32 0)
			(layer "B.Fab")
			(hide yes)
			(effects
				(font
					(size 1 1)
					(thickness 0.15)
				)
				(justify mirror)
			)
		)
		(property "Dielectric" ""
			(at 297.4 146.32 0)
			(layer "B.Fab")
			(hide yes)
			(effects
				(font
					(size 1 1)
					(thickness 0.15)
				)
				(justify mirror)
			)
		)
		(property "License" "Apache-2.0"
			(at 297.4 146.32 0)
			(layer "B.Fab")
			(hide yes)
			(effects
				(font
					(size 1 1)
					(thickness 0.15)
				)
				(justify mirror)
			)
		)
		(property "MPN" "CL10A226MO7JZNC"
			(at 297.4 146.32 0)
			(layer "B.Fab")
			(hide yes)
			(effects
				(font
					(size 1 1)
					(thickness 0.15)
				)
				(justify mirror)
			)
		)
		(property "Manufacturer" "Samsung Electro-Mechanics"
			(at 297.4 146.32 0)
			(layer "B.Fab")
			(hide yes)
			(effects
				(font
					(size 1 1)
					(thickness 0.15)
				)
				(justify mirror)
			)
		)
		(property "Public" "False"
			(at 297.4 146.32 0)
			(layer "B.Fab")
			(hide yes)
			(effects
				(font
					(size 1 1)
					(thickness 0.15)
				)
				(justify mirror)
			)
		)
		(property "Val" "22u"
			(at 297.4 146.32 0)
			(layer "B.Fab")
			(hide yes)
			(effects
				(font
					(size 1 1)
					(thickness 0.15)
				)
				(justify mirror)
			)
		)
		(property "Voltage" "16V"
			(at 297.4 146.32 0)
			(layer "B.Fab")
			(hide yes)
			(effects
				(font
					(size 1 1)
					(thickness 0.15)
				)
				(justify mirror)
			)
		)
		(sheetname "M.2 key E")
		(sheetfile "m2keye.kicad_sch")
		(attr smd)
		(fp_line
			(start 0.15 0.4)
			(end -0.15 0.4)
			(stroke
				(width 0.15)
				(type solid)
			)
			(layer "B.SilkS")
		)
		(fp_line
			(start 0.15 -0.4)
			(end -0.15 -0.4)
			(stroke
				(width 0.15)
				(type solid)
			)
			(layer "B.SilkS")
		)
		(fp_rect
			(start -1.25 0.65)
			(end 1.25 -0.65)
			(stroke
				(width 0.05)
				(type solid)
			)
			(fill no)
			(layer "B.CrtYd")
		)
		(fp_rect
			(start -0.8 0.4)
			(end 0.8 -0.4)
			(stroke
				(width 0.15)
				(type solid)
			)
			(fill no)
			(layer "B.Fab")
		)
		(pad "1" smd roundrect
			(at -0.7 0 180)
			(size 0.8 1)
			(layers "B.Cu" "B.Mask" "B.Paste")
			(roundrect_rratio 0.2)
			(net 1 "GND")
			(pintype "passive")
			(teardrops
				(best_length_ratio 0.2)
				(max_length 1)
				(best_width_ratio 0.9)
				(max_width 2)
				(curved_edges yes)
				(filter_ratio 0.9)
				(enabled yes)
				(allow_two_segments yes)
				(prefer_zone_connections yes)
			)
		)
		(pad "2" smd roundrect
			(at 0.7 0 180)
			(size 0.8 1)
			(layers "B.Cu" "B.Mask" "B.Paste")
			(roundrect_rratio 0.2)
			(net 2 "+3V3")
			(pintype "passive")
			(teardrops
				(best_length_ratio 0.2)
				(max_length 1)
				(best_width_ratio 0.9)
				(max_width 2)
				(curved_edges yes)
				(filter_ratio 0.9)
				(enabled yes)
				(allow_two_segments yes)
				(prefer_zone_connections yes)
			)
		)
	)
	(footprint "antmicro-footprints:C_0402_1005Metric"
		(layer "B.Cu")
		(at 148.95 132.87 180)
		(descr "Capacitor SMD 0402")
		(tags "capacitor SMD 0402")
		(property "Reference" "C170"
			(at 0.45 5.01 0)
			(layer "B.SilkS")
			(effects
				(font
					(size 0.7 0.7)
					(thickness 0.15)
				)
				(justify left bottom mirror)
			)
		)
		(property "Value" "C_100n_0402"
			(at -1.022927 -2.155213 0)
			(layer "B.Fab")
			(effects
				(font
					(size 0.7 0.7)
					(thickness 0.15)
				)
				(justify left bottom mirror)
			)
		)
		(property "Datasheet" "https://www.murata.com/products/productdetail?partno=GRM155R61H104KE14%23"
			(at 0 0 180)
			(layer "F.Fab")
			(hide yes)
			(effects
				(font
					(size 1.27 1.27)
					(thickness 0.15)
				)
			)
		)
		(property "Author" "Antmicro"
			(at 297.9 265.74 0)
			(layer "B.Fab")
			(hide yes)
			(effects
				(font
					(size 1 1)
					(thickness 0.15)
				)
				(justify mirror)
			)
		)
		(property "Dielectric" "X5R"
			(at 297.9 265.74 0)
			(layer "B.Fab")
			(hide yes)
			(effects
				(font
					(size 1 1)
					(thickness 0.15)
				)
				(justify mirror)
			)
		)
		(property "License" "Apache-2.0"
			(at 297.9 265.74 0)
			(layer "B.Fab")
			(hide yes)
			(effects
				(font
					(size 1 1)
					(thickness 0.15)
				)
				(justify mirror)
			)
		)
		(property "MPN" "GRM155R61H104KE14D"
			(at 297.9 265.74 0)
			(layer "B.Fab")
			(hide yes)
			(effects
				(font
					(size 1 1)
					(thickness 0.15)
				)
				(justify mirror)
			)
		)
		(property "Manufacturer" "Murata"
			(at 297.9 265.74 0)
			(layer "B.Fab")
			(hide yes)
			(effects
				(font
					(size 1 1)
					(thickness 0.15)
				)
				(justify mirror)
			)
		)
		(property "Public" "False"
			(at 297.9 265.74 0)
			(layer "B.Fab")
			(hide yes)
			(effects
				(font
					(size 1 1)
					(thickness 0.15)
				)
				(justify mirror)
			)
		)
		(property "Val" "100n"
			(at 297.9 265.74 0)
			(layer "B.Fab")
			(hide yes)
			(effects
				(font
					(size 1 1)
					(thickness 0.15)
				)
				(justify mirror)
			)
		)
		(property "Voltage" "50V"
			(at 297.9 265.74 0)
			(layer "B.Fab")
			(hide yes)
			(effects
				(font
					(size 1 1)
					(thickness 0.15)
				)
				(justify mirror)
			)
		)
		(sheetname "KR to SFI #1")
		(sheetfile "kr_sfi.kicad_sch")
		(attr smd)
		(fp_rect
			(start -0.925 0.47)
			(end 0.925 -0.47)
			(stroke
				(width 0.05)
				(type default)
			)
			(fill no)
			(layer "B.CrtYd")
		)
		(fp_line
			(start 0.504 0.25)
			(end -0.494 0.25)
			(stroke
				(width 0.15)
				(type solid)
			)
			(layer "B.Fab")
		)
		(fp_line
			(start 0.504 -0.248)
			(end 0.504 0.25)
			(stroke
				(width 0.15)
				(type solid)
			)
			(layer "B.Fab")
		)
		(fp_line
			(start -0.494 0.25)
			(end -0.494 -0.248)
			(stroke
				(width 0.15)
				(type solid)
			)
			(layer "B.Fab")
		)
		(fp_line
			(start -0.494 -0.248)
			(end 0.504 -0.248)
			(stroke
				(width 0.15)
				(type solid)
			)
			(layer "B.Fab")
		)
		(pad "1" smd roundrect
			(at -0.48 0 180)
			(size 0.59 0.64)
			(layers "B.Cu" "B.Mask" "B.Paste")
			(roundrect_rratio 0.25)
			(net 1 "GND")
			(pintype "passive")
			(teardrops
				(best_length_ratio 0.2)
				(max_length 1)
				(best_width_ratio 0.9)
				(max_width 2)
				(curved_edges yes)
				(filter_ratio 0.9)
				(enabled yes)
				(allow_two_segments yes)
				(prefer_zone_connections yes)
			)
		)
		(pad "2" smd roundrect
			(at 0.48 0 180)
			(size 0.59 0.64)
			(layers "B.Cu" "B.Mask" "B.Paste")
			(roundrect_rratio 0.25)
			(net 74 "+1V0")
			(pintype "passive")
			(teardrops
				(best_length_ratio 0.2)
				(max_length 1)
				(best_width_ratio 0.9)
				(max_width 2)
				(curved_edges yes)
				(filter_ratio 0.9)
				(enabled yes)
				(allow_two_segments yes)
				(prefer_zone_connections yes)
			)
		)
	)
)
